(kicad_pcb
	(version 20260206)
	(generator "pcbnew")
	(generator_version "10.0")
	(general
		(thickness 1.6)
		(legacy_teardrops no)
	)
	(paper "A4")
	(title_block
		(title "timecard-production-celestica-r4006 — R4006-B0001-02_R01.brd")
		(comment 1 "Time Appliance Project (Time Card) / footprints 743-747 of 1113")
	)
	(layers
		(0 "F.Cu" signal "TOP")
		(4 "In1.Cu" signal "L02_GND1")
		(6 "In2.Cu" signal "L03_SIG1")
		(8 "In3.Cu" signal "L04_GND2")
		(10 "In4.Cu" signal "L05_VCC1")
		(12 "In5.Cu" signal "L06_VCC2")
		(14 "In6.Cu" signal "L07_GND3")
		(16 "In7.Cu" signal "L08_SIG2")
		(18 "In8.Cu" signal "L09_GND4")
		(2 "B.Cu" signal "BOTTOM")
		(9 "F.Adhes" user "F.Adhesive")
		(11 "B.Adhes" user "B.Adhesive")
		(13 "F.Paste" user "Package Geometry/Pastemask Top")
		(15 "B.Paste" user "Package Geometry/Pastemask Bottom")
		(5 "F.SilkS" user "Ref Des/Silkscreen Top")
		(7 "B.SilkS" user "Ref Des/Silkscreen Bottom")
		(1 "F.Mask" user "Board Geometry/Soldermask Top")
		(3 "B.Mask" user "Board Geometry/Soldermask Bottom")
		(17 "Dwgs.User" user "User.Drawings")
		(19 "Cmts.User" user "User.Comments")
		(21 "Eco1.User" user "User.Eco1")
		(23 "Eco2.User" user "User.Eco2")
		(25 "Edge.Cuts" user "Board Geometry/Outline")
		(27 "Margin" user)
		(31 "F.CrtYd" user "Package Geometry/Place Bound Top")
		(29 "B.CrtYd" user "Package Geometry/Place Bound Bottom")
		(35 "F.Fab" user "Ref Des/Assembly Top")
		(33 "B.Fab" user "Ref Des/Assembly Bottom")
	)
	(footprint ""
		(layer "B.Cu")
		(at 83.2358 -88.265 180)
		(property "Reference" "R60"
			(at 0.3048 5.29463 0)
			(unlocked yes)
			(layer "B.SilkS")
			(effects
				(font
					(size 0.7874 0.5842)
					(thickness 0.1524)
				)
				(justify mirror)
			)
		)
		(property "Value" "VAL*"
			(at -0.02032 2.13233 180)
			(unlocked yes)
			(layer "B.Fab")
			(hide yes)
			(effects
				(font
					(size 0.7874 0.5842)
					(thickness 0.1524)
				)
				(justify mirror)
			)
		)
		(property "Tolerance" "TOL*"
			(at -0.044704 3.05435 180)
			(unlocked yes)
			(layer "Cmts.User")
			(hide yes)
			(effects
				(font
					(size 0.7874 0.5842)
					(thickness 0.1524)
				)
				(justify mirror)
			)
		)
		(property "User Part Number" "PARTNUM*"
			(at -0.02032 4.024884 180)
			(unlocked yes)
			(layer "Cmts.User")
			(hide yes)
			(effects
				(font
					(size 0.7874 0.5842)
					(thickness 0.1524)
				)
				(justify mirror)
			)
		)
		(property "Device Type" "RESISTOR-G155-133R0-01,33OHM,1%"
			(at -0.008382 1.210564 180)
			(unlocked yes)
			(layer "B.Fab")
			(hide yes)
			(effects
				(font
					(size 0.7874 0.5842)
					(thickness 0.1524)
				)
				(justify mirror)
			)
		)
		(duplicate_pad_numbers_are_jumpers no)
		(fp_line
			(start 1.143 0.5588)
			(end -1.143 0.5588)
			(stroke
				(width 0.1)
				(type default)
			)
			(layer "B.SilkS")
		)
		(fp_line
			(start 1.143 -0.5588)
			(end 1.143 0.5588)
			(stroke
				(width 0.1)
				(type default)
			)
			(layer "B.SilkS")
		)
		(fp_line
			(start -1.143 0.5588)
			(end -1.143 -0.5588)
			(stroke
				(width 0.1)
				(type default)
			)
			(layer "B.SilkS")
		)
		(fp_line
			(start -1.143 -0.5588)
			(end 1.143 -0.5588)
			(stroke
				(width 0.1)
				(type default)
			)
			(layer "B.SilkS")
		)
		(fp_rect
			(start 1.143 -0.5588)
			(end -1.143 0.5588)
			(stroke
				(width 0)
				(type default)
			)
			(fill no)
			(layer "B.CrtYd")
		)
		(fp_line
			(start 0.508 0.3048)
			(end -0.508 0.3048)
			(stroke
				(width 0.1)
				(type default)
			)
			(layer "B.Fab")
		)
		(fp_line
			(start 0.508 -0.3048)
			(end 0.508 0.3048)
			(stroke
				(width 0.1)
				(type default)
			)
			(layer "B.Fab")
		)
		(fp_line
			(start -0.508 0.3048)
			(end -0.508 -0.3048)
			(stroke
				(width 0.1)
				(type default)
			)
			(layer "B.Fab")
		)
		(fp_line
			(start -0.508 -0.3048)
			(end 0.508 -0.3048)
			(stroke
				(width 0.1)
				(type default)
			)
			(layer "B.Fab")
		)
		(pad "1" smd rect
			(at 0.5334 0)
			(size 0.7112 0.6096)
			(layers "B.Cu" "B.Mask" "B.Paste")
			(net "FPGA_OUT_PCA9546_RST_N")
		)
		(pad "2" smd rect
			(at -0.5334 0)
			(size 0.7112 0.6096)
			(layers "B.Cu" "B.Mask" "B.Paste")
			(net "PCA9546_RST_N")
		)
		(zone
			(layer "B.Cu")
			(hatch none 0.5)
			(connect_pads
				(clearance 0)
			)
			(min_thickness 0.25)
			(keepout
				(tracks allowed)
				(vias not_allowed)
				(pads allowed)
				(copperpour not_allowed)
				(footprints allowed)
			)
			(placement
				(enabled no)
				(sheetname "")
			)
			(fill
				(thermal_gap 0.5)
				(thermal_bridge_width 0.5)
				(island_removal_mode 0)
			)
			(polygon
				(pts
					(xy 83.1596 -87.9602) (xy 83.312 -87.9602) (xy 83.312 -88.5698) (xy 83.1596 -88.5698)
				)
			)
		)
	)
	(footprint ""
		(layer "B.Cu")
		(at 109.347 -39.878 -90)
		(property "Reference" "C133"
			(at 1.651 41.63695 270)
			(unlocked yes)
			(layer "B.SilkS")
			(effects
				(font
					(size 0.635 0.4064)
					(thickness 0.1524)
				)
				(justify mirror)
			)
		)
		(property "Value" "VAL*"
			(at -0.0762 2.067306 270)
			(unlocked yes)
			(layer "B.Fab")
			(hide yes)
			(effects
				(font
					(size 0.7874 0.5842)
					(thickness 0.1524)
				)
				(justify mirror)
			)
		)
		(property "Device Type" "CAPACITOR-G105-0B104-CK,0.1UF,A"
			(at -0.0508 1.127506 270)
			(unlocked yes)
			(layer "B.Fab")
			(hide yes)
			(effects
				(font
					(size 0.7874 0.5842)
					(thickness 0.1524)
				)
				(justify mirror)
			)
		)
		(property "User Part Number" "PARTNUM*"
			(at -0.1016 4.023106 270)
			(unlocked yes)
			(layer "Cmts.User")
			(hide yes)
			(effects
				(font
					(size 0.7874 0.5842)
					(thickness 0.1524)
				)
				(justify mirror)
			)
		)
		(property "Tolerance" "TOL*"
			(at -0.0762 3.032506 270)
			(unlocked yes)
			(layer "Cmts.User")
			(hide yes)
			(effects
				(font
					(size 0.7874 0.5842)
					(thickness 0.1524)
				)
				(justify mirror)
			)
		)
		(duplicate_pad_numbers_are_jumpers no)
		(fp_line
			(start -1.143 0.5588)
			(end -1.143 -0.5588)
			(stroke
				(width 0.1)
				(type default)
			)
			(layer "B.SilkS")
		)
		(fp_line
			(start 1.143 0.5588)
			(end -1.143 0.5588)
			(stroke
				(width 0.1)
				(type default)
			)
			(layer "B.SilkS")
		)
		(fp_line
			(start -1.143 -0.5588)
			(end 1.143 -0.5588)
			(stroke
				(width 0.1)
				(type default)
			)
			(layer "B.SilkS")
		)
		(fp_line
			(start 1.143 -0.5588)
			(end 1.143 0.5588)
			(stroke
				(width 0.1)
				(type default)
			)
			(layer "B.SilkS")
		)
		(fp_rect
			(start 1.143 0.5588)
			(end -1.143 -0.5588)
			(stroke
				(width 0)
				(type default)
			)
			(fill no)
			(layer "B.CrtYd")
		)
		(fp_line
			(start -0.508 0.3048)
			(end -0.508 -0.3048)
			(stroke
				(width 0.1)
				(type default)
			)
			(layer "B.Fab")
		)
		(fp_line
			(start 0.508 0.3048)
			(end -0.508 0.3048)
			(stroke
				(width 0.1)
				(type default)
			)
			(layer "B.Fab")
		)
		(fp_line
			(start -0.508 -0.3048)
			(end 0.508 -0.3048)
			(stroke
				(width 0.1)
				(type default)
			)
			(layer "B.Fab")
		)
		(fp_line
			(start 0.508 -0.3048)
			(end 0.508 0.3048)
			(stroke
				(width 0.1)
				(type default)
			)
			(layer "B.Fab")
		)
		(pad "1" smd rect
			(at 0.5334 0 90)
			(size 0.7112 0.6096)
			(layers "B.Cu" "B.Mask" "B.Paste")
			(net "XP1R0V_FPGA_VCCINT")
		)
		(pad "2" smd rect
			(at -0.5334 0 90)
			(size 0.7112 0.6096)
			(layers "B.Cu" "B.Mask" "B.Paste")
			(net "SG")
		)
		(zone
			(layer "B.Cu")
			(hatch none 0.5)
			(connect_pads
				(clearance 0)
			)
			(min_thickness 0.25)
			(keepout
				(tracks allowed)
				(vias not_allowed)
				(pads allowed)
				(copperpour not_allowed)
				(footprints allowed)
			)
			(placement
				(enabled no)
				(sheetname "")
			)
			(fill
				(thermal_gap 0.5)
				(thermal_bridge_width 0.5)
				(island_removal_mode 0)
			)
			(polygon
				(pts
					(xy 109.0422 -39.8018) (xy 109.6518 -39.8018) (xy 109.6518 -39.9542) (xy 109.0422 -39.9542)
				)
			)
		)
	)
	(footprint ""
		(layer "B.Cu")
		(at 127.254 -87.757 180)
		(property "Reference" "R269"
			(at -2.794 -0.16637 0)
			(unlocked yes)
			(layer "B.SilkS")
			(effects
				(font
					(size 0.7874 0.5842)
					(thickness 0.1524)
				)
				(justify mirror)
			)
		)
		(property "Value" "VAL*"
			(at -0.02032 2.13233 180)
			(unlocked yes)
			(layer "B.Fab")
			(hide yes)
			(effects
				(font
					(size 0.7874 0.5842)
					(thickness 0.1524)
				)
				(justify mirror)
			)
		)
		(property "Tolerance" "TOL*"
			(at -0.044704 3.05435 180)
			(unlocked yes)
			(layer "Cmts.User")
			(hide yes)
			(effects
				(font
					(size 0.7874 0.5842)
					(thickness 0.1524)
				)
				(justify mirror)
			)
		)
		(property "User Part Number" "PARTNUM*"
			(at -0.02032 4.024884 180)
			(unlocked yes)
			(layer "Cmts.User")
			(hide yes)
			(effects
				(font
					(size 0.7874 0.5842)
					(thickness 0.1524)
				)
				(justify mirror)
			)
		)
		(property "Device Type" "RESISTOR-G155-11003-01,100KOHMA"
			(at -0.008382 1.210564 180)
			(unlocked yes)
			(layer "B.Fab")
			(hide yes)
			(effects
				(font
					(size 0.7874 0.5842)
					(thickness 0.1524)
				)
				(justify mirror)
			)
		)
		(duplicate_pad_numbers_are_jumpers no)
		(fp_line
			(start 1.143 0.5588)
			(end -1.143 0.5588)
			(stroke
				(width 0.1)
				(type default)
			)
			(layer "B.SilkS")
		)
		(fp_line
			(start 1.143 -0.5588)
			(end 1.143 0.5588)
			(stroke
				(width 0.1)
				(type default)
			)
			(layer "B.SilkS")
		)
		(fp_line
			(start -1.143 0.5588)
			(end -1.143 -0.5588)
			(stroke
				(width 0.1)
				(type default)
			)
			(layer "B.SilkS")
		)
		(fp_line
			(start -1.143 -0.5588)
			(end 1.143 -0.5588)
			(stroke
				(width 0.1)
				(type default)
			)
			(layer "B.SilkS")
		)
		(fp_rect
			(start -1.143 -0.5588)
			(end 1.143 0.5588)
			(stroke
				(width 0)
				(type default)
			)
			(fill no)
			(layer "B.CrtYd")
		)
		(fp_line
			(start 0.508 0.3048)
			(end -0.508 0.3048)
			(stroke
				(width 0.1)
				(type default)
			)
			(layer "B.Fab")
		)
		(fp_line
			(start 0.508 -0.3048)
			(end 0.508 0.3048)
			(stroke
				(width 0.1)
				(type default)
			)
			(layer "B.Fab")
		)
		(fp_line
			(start -0.508 0.3048)
			(end -0.508 -0.3048)
			(stroke
				(width 0.1)
				(type default)
			)
			(layer "B.Fab")
		)
		(fp_line
			(start -0.508 -0.3048)
			(end 0.508 -0.3048)
			(stroke
				(width 0.1)
				(type default)
			)
			(layer "B.Fab")
		)
		(pad "1" smd rect
			(at 0.5334 0)
			(size 0.7112 0.6096)
			(layers "B.Cu" "B.Mask" "B.Paste")
			(net "XP3R3V_FPGA")
		)
		(pad "2" smd rect
			(at -0.5334 0)
			(size 0.7112 0.6096)
			(layers "B.Cu" "B.Mask" "B.Paste")
			(net "UART_GPS_TX_FPGA_RX")
		)
		(zone
			(layer "B.Cu")
			(hatch none 0.5)
			(connect_pads
				(clearance 0)
			)
			(min_thickness 0.25)
			(keepout
				(tracks not_allowed)
				(vias allowed)
				(pads allowed)
				(copperpour not_allowed)
				(footprints allowed)
			)
			(placement
				(enabled no)
				(sheetname "")
			)
			(fill
				(thermal_gap 0.5)
				(thermal_bridge_width 0.5)
				(island_removal_mode 0)
			)
			(polygon
				(pts
					(xy 127.3302 -87.4522) (xy 127.3302 -88.0618) (xy 127.1778 -88.0618) (xy 127.1778 -87.4522)
				)
			)
		)
		(zone
			(layer "B.Cu")
			(hatch none 0.5)
			(connect_pads
				(clearance 0)
			)
			(min_thickness 0.25)
			(keepout
				(tracks allowed)
				(vias not_allowed)
				(pads allowed)
				(copperpour not_allowed)
				(footprints allowed)
			)
			(placement
				(enabled no)
				(sheetname "")
			)
			(fill
				(thermal_gap 0.5)
				(thermal_bridge_width 0.5)
				(island_removal_mode 0)
			)
			(polygon
				(pts
					(xy 127.3302 -87.4522) (xy 127.3302 -88.0618) (xy 127.1778 -88.0618) (xy 127.1778 -87.4522)
				)
			)
		)
	)
	(footprint ""
		(layer "B.Cu")
		(at 101.847142 -39.323264 -90)
		(property "Reference" "C218"
			(at 1.268984 42.018712 270)
			(unlocked yes)
			(layer "B.SilkS")
			(effects
				(font
					(size 0.635 0.4064)
					(thickness 0.1524)
				)
				(justify mirror)
			)
		)
		(property "Value" "VAL*"
			(at 0 3.718306 270)
			(unlocked yes)
			(layer "B.Fab")
			(hide yes)
			(effects
				(font
					(size 0.7874 0.5842)
					(thickness 0.127)
				)
				(justify mirror)
			)
		)
		(property "Tolerance" "TOL*"
			(at 0 4.861306 270)
			(unlocked yes)
			(layer "Cmts.User")
			(hide yes)
			(effects
				(font
					(size 0.7874 0.5842)
					(thickness 0.127)
				)
				(justify mirror)
			)
		)
		(property "User Part Number" "PARTNUM*"
			(at 0 2.575306 270)
			(unlocked yes)
			(layer "Cmts.User")
			(hide yes)
			(effects
				(font
					(size 0.7874 0.5842)
					(thickness 0.127)
				)
				(justify mirror)
			)
		)
		(property "Device Type" "CAPACITOR-G105-0B104-CK,0.1UF,A"
			(at 0 1.432306 270)
			(unlocked yes)
			(layer "B.Fab")
			(hide yes)
			(effects
				(font
					(size 0.7874 0.5842)
					(thickness 0.127)
				)
				(justify mirror)
			)
		)
		(duplicate_pad_numbers_are_jumpers no)
		(fp_line
			(start -0.970026 0.4699)
			(end 0.970026 0.4699)
			(stroke
				(width 0.1)
				(type default)
			)
			(layer "B.SilkS")
		)
		(fp_line
			(start 0.970026 0.4699)
			(end 0.970026 -0.4699)
			(stroke
				(width 0.1)
				(type default)
			)
			(layer "B.SilkS")
		)
		(fp_line
			(start -0.970026 -0.4699)
			(end -0.970026 0.4699)
			(stroke
				(width 0.1)
				(type default)
			)
			(layer "B.SilkS")
		)
		(fp_line
			(start 0.970026 -0.4699)
			(end -0.970026 -0.4699)
			(stroke
				(width 0.1)
				(type default)
			)
			(layer "B.SilkS")
		)
		(fp_poly
			(pts
				(xy 0.970026 0.4699) (xy -0.970026 0.4699) (xy -0.970026 -0.4699) (xy 0.970026 -0.4699)
			)
			(stroke
				(width 0)
				(type default)
			)
			(fill no)
			(layer "B.CrtYd")
		)
		(fp_line
			(start -0.508 0.3048)
			(end 0.508 0.3048)
			(stroke
				(width 0.1)
				(type default)
			)
			(layer "B.Fab")
		)
		(fp_line
			(start 0.508 0.3048)
			(end 0.508 -0.3048)
			(stroke
				(width 0.1)
				(type default)
			)
			(layer "B.Fab")
		)
		(fp_line
			(start -0.508 -0.3048)
			(end -0.508 0.3048)
			(stroke
				(width 0.1)
				(type default)
			)
			(layer "B.Fab")
		)
		(fp_line
			(start 0.508 -0.3048)
			(end -0.508 -0.3048)
			(stroke
				(width 0.1)
				(type default)
			)
			(layer "B.Fab")
		)
		(pad "1" smd circle
			(at 0.500126 0 90)
			(size 0.635 0.635)
			(layers "B.Cu" "B.Mask" "B.Paste")
			(net "XP1R0V_FPGA_MGTAVCC")
		)
		(pad "2" smd circle
			(at -0.500126 0 90)
			(size 0.635 0.635)
			(layers "B.Cu" "B.Mask" "B.Paste")
			(net "SG")
		)
	)
	(footprint ""
		(layer "B.Cu")
		(at 18.415 -81.28 180)
		(property "Reference" "R479"
			(at -3.81 -0.42037 0)
			(unlocked yes)
			(layer "B.SilkS")
			(effects
				(font
					(size 0.7874 0.5842)
					(thickness 0.1524)
				)
				(justify mirror)
			)
		)
		(property "Value" "VAL*"
			(at -0.02032 2.13233 180)
			(unlocked yes)
			(layer "B.Fab")
			(hide yes)
			(effects
				(font
					(size 0.7874 0.5842)
					(thickness 0.1524)
				)
				(justify mirror)
			)
		)
		(property "Tolerance" "TOL*"
			(at -0.044704 3.05435 180)
			(unlocked yes)
			(layer "Cmts.User")
			(hide yes)
			(effects
				(font
					(size 0.7874 0.5842)
					(thickness 0.1524)
				)
				(justify mirror)
			)
		)
		(property "User Part Number" "PARTNUM*"
			(at -0.02032 4.024884 180)
			(unlocked yes)
			(layer "Cmts.User")
			(hide yes)
			(effects
				(font
					(size 0.7874 0.5842)
					(thickness 0.1524)
				)
				(justify mirror)
			)
		)
		(property "Device Type" "RESISTOR-G155-11003-01,100KOHMA"
			(at -0.008382 1.210564 180)
			(unlocked yes)
			(layer "B.Fab")
			(hide yes)
			(effects
				(font
					(size 0.7874 0.5842)
					(thickness 0.1524)
				)
				(justify mirror)
			)
		)
		(duplicate_pad_numbers_are_jumpers no)
		(fp_line
			(start 1.143 0.5588)
			(end -1.143 0.5588)
			(stroke
				(width 0.1)
				(type default)
			)
			(layer "B.SilkS")
		)
		(fp_line
			(start 1.143 -0.5588)
			(end 1.143 0.5588)
			(stroke
				(width 0.1)
				(type default)
			)
			(layer "B.SilkS")
		)
		(fp_line
			(start -1.143 0.5588)
			(end -1.143 -0.5588)
			(stroke
				(width 0.1)
				(type default)
			)
			(layer "B.SilkS")
		)
		(fp_line
			(start -1.143 -0.5588)
			(end 1.143 -0.5588)
			(stroke
				(width 0.1)
				(type default)
			)
			(layer "B.SilkS")
		)
		(fp_poly
			(pts
				(xy 1.143 0.5588) (xy -1.143 0.5588) (xy -1.143 -0.5588) (xy 1.143 -0.5588)
			)
			(stroke
				(width 0)
				(type default)
			)
			(fill no)
			(layer "B.CrtYd")
		)
		(fp_line
			(start 0.508 0.3048)
			(end -0.508 0.3048)
			(stroke
				(width 0.1)
				(type default)
			)
			(layer "B.Fab")
		)
		(fp_line
			(start 0.508 -0.3048)
			(end 0.508 0.3048)
			(stroke
				(width 0.1)
				(type default)
			)
			(layer "B.Fab")
		)
		(fp_line
			(start -0.508 0.3048)
			(end -0.508 -0.3048)
			(stroke
				(width 0.1)
				(type default)
			)
			(layer "B.Fab")
		)
		(fp_line
			(start -0.508 -0.3048)
			(end 0.508 -0.3048)
			(stroke
				(width 0.1)
				(type default)
			)
			(layer "B.Fab")
		)
		(pad "1" smd rect
			(at 0.5334 0)
			(size 0.7112 0.6096)
			(layers "B.Cu" "B.Mask" "B.Paste")
			(net "FT4232_I2C_SDA")
		)
		(pad "2" smd rect
			(at -0.5334 0)
			(size 0.7112 0.6096)
			(layers "B.Cu" "B.Mask" "B.Paste")
			(net "XP3R3V_FT4232")
		)
		(zone
			(layer "B.Cu")
			(hatch none 0.5)
			(connect_pads
				(clearance 0)
			)
			(min_thickness 0.25)
			(keepout
				(tracks not_allowed)
				(vias allowed)
				(pads allowed)
				(copperpour not_allowed)
				(footprints allowed)
			)
			(placement
				(enabled no)
				(sheetname "")
			)
			(fill
				(thermal_gap 0.5)
				(thermal_bridge_width 0.5)
				(island_removal_mode 0)
			)
			(polygon
				(pts
					(xy 18.3388 -81.5848) (xy 18.3388 -80.9752) (xy 18.4912 -80.9752) (xy 18.4912 -81.5848)
				)
			)
		)
		(zone
			(layer "B.Cu")
			(hatch none 0.5)
			(connect_pads
				(clearance 0)
			)
			(min_thickness 0.25)
			(keepout
				(tracks allowed)
				(vias not_allowed)
				(pads allowed)
				(copperpour not_allowed)
				(footprints allowed)
			)
			(placement
				(enabled no)
				(sheetname "")
			)
			(fill
				(thermal_gap 0.5)
				(thermal_bridge_width 0.5)
				(island_removal_mode 0)
			)
			(polygon
				(pts
					(xy 18.3388 -81.5848) (xy 18.3388 -80.9752) (xy 18.4912 -80.9752) (xy 18.4912 -81.5848)
				)
			)
		)
	)
)
